# BASEBOARD_FAB2 (Tioga Pass) — schematic netlist excerpt (pin names and nets, part order shuffled) for the footprints in the layout excerpt that follows; sources: Cadence DE-HDL packaged netlist, KiCad conversion of Wiwynn_Tioga_Pass_MB.brd

C8U1  CAP  100UF 4V 20% X5R  pkg 0805  page 225 : A = PVDDQ_GHJ ; B = GND
C9E1  CAP_A  22.0UF 4V 20% EMPTY  pkg 0603V  page 139 : A = P0V9_LAN ; B = GND
C25P80  CAP_A  0.1UF 16V 10% X7R  pkg 0402V  page 252 : A = P5V_VGA_D ; B = GND

(kicad_pcb
	(version 20260206)
	(generator "pcbnew")
	(generator_version "10.0")
	(general
		(thickness 1.6)
		(legacy_teardrops no)
	)
	(paper "A4")
	(title_block
		(title "Wiwynn_Tioga_Pass_MB.brd")
		(comment 1 "Tioga Pass / footprints 3685-3687 of 4770")
	)
	(layers
		(0 "F.Cu" signal "TOP")
		(4 "In1.Cu" signal "L2GND")
		(6 "In2.Cu" signal "L3")
		(8 "In3.Cu" signal "L4GND")
		(10 "In4.Cu" signal "L5")
		(12 "In5.Cu" signal "L6GND")
		(14 "In6.Cu" signal "L7VCC")
		(16 "In7.Cu" signal "L8VCC")
		(18 "In8.Cu" signal "L9GND")
		(20 "In9.Cu" signal "L10")
		(22 "In10.Cu" signal "L11GND")
		(24 "In11.Cu" signal "L12")
		(26 "In12.Cu" signal "L13GND")
		(2 "B.Cu" signal "BOTTOM")
		(9 "F.Adhes" user "F.Adhesive")
		(11 "B.Adhes" user "B.Adhesive")
		(13 "F.Paste" user "Package Geometry/Pastemask Top")
		(15 "B.Paste" user "Package Geometry/Pastemask Bottom")
		(5 "F.SilkS" user "Ref Des/Silkscreen Top")
		(7 "B.SilkS" user "Ref Des/Silkscreen Bottom")
		(1 "F.Mask" user "Board Geometry/Soldermask Top")
		(3 "B.Mask" user "Board Geometry/Soldermask Bottom")
		(17 "Dwgs.User" user "User.Drawings")
		(19 "Cmts.User" user "User.Comments")
		(21 "Eco1.User" user "User.Eco1")
		(23 "Eco2.User" user "User.Eco2")
		(25 "Edge.Cuts" user "Board Geometry/Outline")
		(27 "Margin" user)
		(31 "F.CrtYd" user "Package Geometry/Place Bound Top")
		(29 "B.CrtYd" user "Package Geometry/Place Bound Bottom")
		(35 "F.Fab" user "Ref Des/Assembly Top")
		(33 "B.Fab" user "Ref Des/Assembly Bottom")
	)
	(footprint ""
		(layer "B.Cu")
		(at 488.191302 -46.854872 -90)
		(property "Reference" "C9E1"
			(at 0 0 90)
			(layer "B.SilkS")
			(hide yes)
			(effects
				(font
					(size 1.27 1.27)
				)
				(justify mirror)
			)
		)
		(property "Value" ""
			(at 0 0 90)
			(layer "B.Fab")
			(effects
				(font
					(size 1.27 1.27)
				)
				(justify mirror)
			)
		)
		(duplicate_pad_numbers_are_jumpers no)
		(fp_poly
			(pts
				(xy 0.4953 -0.2032) (xy -0.4953 -0.2032) (xy -0.4953 1.6002) (xy 0.4953 1.6002)
			)
			(stroke
				(width 0)
				(type default)
			)
			(fill no)
			(layer "B.CrtYd")
		)
		(fp_line
			(start -0.4953 1.6002)
			(end 0.4953 1.6002)
			(stroke
				(width 0.1)
				(type default)
			)
			(layer "B.Fab")
		)
		(fp_line
			(start 0.4953 1.6002)
			(end 0.4953 -0.2032)
			(stroke
				(width 0.1)
				(type default)
			)
			(layer "B.Fab")
		)
		(fp_line
			(start -0.4953 -0.2032)
			(end -0.4953 1.6002)
			(stroke
				(width 0.1)
				(type default)
			)
			(layer "B.Fab")
		)
		(fp_line
			(start 0.4953 -0.2032)
			(end -0.4953 -0.2032)
			(stroke
				(width 0.1)
				(type default)
			)
			(layer "B.Fab")
		)
		(pad "1" smd rect
			(at 0 0 90)
			(size 0.762 0.889)
			(layers "B.Cu" "B.Mask" "B.Paste")
			(net "P0V9_LAN")
		)
		(pad "2" smd rect
			(at 0 1.397 90)
			(size 0.762 0.889)
			(layers "B.Cu" "B.Mask" "B.Paste")
			(net "GND")
		)
		(zone
			(layer "B.Cu")
			(hatch none 0.5)
			(connect_pads
				(clearance 0)
			)
			(min_thickness 0.25)
			(keepout
				(tracks not_allowed)
				(vias allowed)
				(pads allowed)
				(copperpour not_allowed)
				(footprints allowed)
			)
			(placement
				(enabled no)
				(sheetname "")
			)
			(fill
				(thermal_gap 0.5)
				(thermal_bridge_width 0.5)
				(island_removal_mode 0)
			)
			(polygon
				(pts
					(xy 487.746802 -46.473872) (xy 487.746802 -47.235872) (xy 487.238802 -47.235872) (xy 487.238802 -46.473872)
				)
			)
		)
	)
	(footprint ""
		(layer "B.Cu")
		(at 94.460568 -17.5514 90)
		(property "Reference" "C8U1"
			(at 0 0 90)
			(layer "B.SilkS")
			(hide yes)
			(effects
				(font
					(size 1.27 1.27)
				)
				(justify mirror)
			)
		)
		(property "Value" ""
			(at 0 0 90)
			(layer "B.Fab")
			(effects
				(font
					(size 1.27 1.27)
				)
				(justify mirror)
			)
		)
		(duplicate_pad_numbers_are_jumpers no)
		(fp_poly
			(pts
				(xy 0.7239 -0.2159) (xy -0.7239 -0.2159) (xy -0.7239 1.9939) (xy 0.7239 1.9939)
			)
			(stroke
				(width 0)
				(type default)
			)
			(fill no)
			(layer "B.CrtYd")
		)
		(fp_line
			(start 0.7239 -0.2159)
			(end 0.7239 1.9939)
			(stroke
				(width 0.1)
				(type default)
			)
			(layer "B.Fab")
		)
		(fp_line
			(start -0.7239 -0.2159)
			(end 0.7239 -0.2159)
			(stroke
				(width 0.1)
				(type default)
			)
			(layer "B.Fab")
		)
		(fp_line
			(start 0.7239 1.9939)
			(end -0.7239 1.9939)
			(stroke
				(width 0.1)
				(type default)
			)
			(layer "B.Fab")
		)
		(fp_line
			(start -0.7239 1.9939)
			(end -0.7239 -0.2159)
			(stroke
				(width 0.1)
				(type default)
			)
			(layer "B.Fab")
		)
		(pad "1" smd rect
			(at 0 0 270)
			(size 1.27 1.016)
			(layers "B.Cu" "B.Mask" "B.Paste")
			(net "PVDDQ_GHJ")
		)
		(pad "2" smd rect
			(at 0 1.778 270)
			(size 1.27 1.016)
			(layers "B.Cu" "B.Mask" "B.Paste")
			(net "GND")
		)
		(zone
			(layer "B.Cu")
			(hatch none 0.5)
			(connect_pads
				(clearance 0)
			)
			(min_thickness 0.25)
			(keepout
				(tracks not_allowed)
				(vias allowed)
				(pads allowed)
				(copperpour not_allowed)
				(footprints allowed)
			)
			(placement
				(enabled no)
				(sheetname "")
			)
			(fill
				(thermal_gap 0.5)
				(thermal_bridge_width 0.5)
				(island_removal_mode 0)
			)
			(polygon
				(pts
					(xy 94.968568 -18.1864) (xy 94.968568 -16.9164) (xy 95.730568 -16.9164) (xy 95.730568 -18.1864)
				)
			)
		)
	)
	(footprint ""
		(layer "B.Cu")
		(at 497.561108 -41.41343)
		(property "Reference" "C25P80"
			(at 0.8382 -0.67818 0)
			(unlocked yes)
			(layer "B.SilkS")
			(effects
				(font
					(size 0.4064 0.254)
					(thickness 0.1524)
				)
				(justify left mirror)
			)
		)
		(property "Value" ""
			(at 0 0 0)
			(layer "B.Fab")
			(effects
				(font
					(size 1.27 1.27)
				)
				(justify mirror)
			)
		)
		(duplicate_pad_numbers_are_jumpers no)
		(fp_poly
			(pts
				(xy -0.3048 -0.1016) (xy -0.3048 0.9906) (xy 0.3048 0.9906) (xy 0.3048 -0.1016)
			)
			(stroke
				(width 0)
				(type default)
			)
			(fill no)
			(layer "B.CrtYd")
		)
		(fp_line
			(start -0.3048 -0.1016)
			(end 0.3048 -0.1016)
			(stroke
				(width 0.1)
				(type default)
			)
			(layer "B.Fab")
		)
		(fp_line
			(start -0.3048 0.9906)
			(end -0.3048 -0.1016)
			(stroke
				(width 0.1)
				(type default)
			)
			(layer "B.Fab")
		)
		(fp_line
			(start 0.3048 -0.1016)
			(end 0.3048 0.9906)
			(stroke
				(width 0.1)
				(type default)
			)
			(layer "B.Fab")
		)
		(fp_line
			(start 0.3048 0.9906)
			(end -0.3048 0.9906)
			(stroke
				(width 0.1)
				(type default)
			)
			(layer "B.Fab")
		)
		(pad "1" smd rect
			(at 0 0 180)
			(size 0.508 0.508)
			(layers "B.Cu" "B.Mask" "B.Paste")
			(net "P5V_VGA_D")
		)
		(pad "2" smd rect
			(at 0 0.889 180)
			(size 0.508 0.508)
			(layers "B.Cu" "B.Mask" "B.Paste")
			(net "GND")
		)
		(zone
			(layer "B.Cu")
			(hatch none 0.5)
			(connect_pads
				(clearance 0)
			)
			(min_thickness 0.25)
			(keepout
				(tracks allowed)
				(vias not_allowed)
				(pads allowed)
				(copperpour not_allowed)
				(footprints allowed)
			)
			(placement
				(enabled no)
				(sheetname "")
			)
			(fill
				(thermal_gap 0.5)
				(thermal_bridge_width 0.5)
				(island_removal_mode 0)
			)
			(polygon
				(pts
					(xy 497.815108 -41.15943) (xy 497.307108 -41.15943) (xy 497.307108 -40.77843) (xy 497.815108 -40.77843)
				)
			)
		)
		(zone
			(layer "B.Cu")
			(hatch none 0.5)
			(connect_pads
				(clearance 0)
			)
			(min_thickness 0.25)
			(keepout
				(tracks not_allowed)
				(vias allowed)
				(pads allowed)
				(copperpour not_allowed)
				(footprints allowed)
			)
			(placement
				(enabled no)
				(sheetname "")
			)
			(fill
				(thermal_gap 0.5)
				(thermal_bridge_width 0.5)
				(island_removal_mode 0)
			)
			(polygon
				(pts
					(xy 497.815108 -40.77843) (xy 497.307108 -40.77843) (xy 497.307108 -41.15943) (xy 497.815108 -41.15943)
				)
			)
		)
	)
)
